(kicad_pcb
	(version 20260206)
	(generator "pcbnew")
	(generator_version "10.0")
	(general
		(thickness 1.6)
		(legacy_teardrops no)
	)
	(paper "A4")
	(title_block
		(title "v1-pdb — T6M_PDB_D_0927_0900.brd")
		(comment 1 "Open CloudServer (Microsoft) / footprints 151-152 of 321")
	)
	(layers
		(0 "F.Cu" signal "TOP")
		(4 "In1.Cu" signal "GND")
		(6 "In2.Cu" signal "IN1")
		(8 "In3.Cu" signal "VCC")
		(10 "In4.Cu" signal "VCC1")
		(12 "In5.Cu" signal "IN2")
		(14 "In6.Cu" signal "GND1")
		(2 "B.Cu" signal "BOTTOM")
		(9 "F.Adhes" user "F.Adhesive")
		(11 "B.Adhes" user "B.Adhesive")
		(13 "F.Paste" user "Package Geometry/Pastemask Top")
		(15 "B.Paste" user "Package Geometry/Pastemask Bottom")
		(5 "F.SilkS" user "Ref Des/Silkscreen Top")
		(7 "B.SilkS" user "Ref Des/Silkscreen Bottom")
		(1 "F.Mask" user "Board Geometry/Soldermask Top")
		(3 "B.Mask" user "Board Geometry/Soldermask Bottom")
		(17 "Dwgs.User" user "User.Drawings")
		(19 "Cmts.User" user "User.Comments")
		(21 "Eco1.User" user "User.Eco1")
		(23 "Eco2.User" user "User.Eco2")
		(25 "Edge.Cuts" user "Board Geometry/Outline")
		(27 "Margin" user)
		(31 "F.CrtYd" user "Package Geometry/Place Bound Top")
		(29 "B.CrtYd" user "Package Geometry/Place Bound Bottom")
		(35 "F.Fab" user "Ref Des/Assembly Top")
		(33 "B.Fab" user "Ref Des/Assembly Bottom")
	)
	(footprint ""
		(layer "F.Cu")
		(at 30.45968 -83.330034)
		(property "Reference" "J1"
			(at 7.517892 2.350516 0)
			(unlocked yes)
			(layer "F.SilkS")
			(effects
				(font
					(size 0.7874 0.5842)
					(thickness 0.1524)
				)
				(justify left)
			)
		)
		(property "Value" ""
			(at 0 0 0)
			(layer "F.Fab")
			(effects
				(font
					(size 1.27 1.27)
				)
			)
		)
		(duplicate_pad_numbers_are_jumpers no)
		(fp_line
			(start -2.135124 -4.560062)
			(end -2.135124 83.300062)
			(stroke
				(width 0.1524)
				(type default)
			)
			(layer "F.SilkS")
		)
		(fp_line
			(start -2.135124 83.300062)
			(end 7.215124 83.300062)
			(stroke
				(width 0.1524)
				(type default)
			)
			(layer "F.SilkS")
		)
		(fp_line
			(start 7.215124 -4.560062)
			(end -2.135124 -4.560062)
			(stroke
				(width 0.1524)
				(type default)
			)
			(layer "F.SilkS")
		)
		(fp_line
			(start 7.215124 83.300062)
			(end 7.215124 -4.560062)
			(stroke
				(width 0.1524)
				(type default)
			)
			(layer "F.SilkS")
		)
		(fp_poly
			(pts
				(xy -2.467864 0.208026) (xy -5.167884 -0.491998) (xy -5.167884 0.90805)
			)
			(stroke
				(width 0)
				(type default)
			)
			(fill yes)
			(layer "F.SilkS")
		)
		(fp_poly
			(pts
				(xy -2.28219 -0.127) (xy -4.98221 -0.827024) (xy -4.98221 0.573024)
			)
			(stroke
				(width 0)
				(type default)
			)
			(fill yes)
			(layer "B.SilkS")
		)
		(fp_poly
			(pts
				(xy -0.8636 -0.8636) (xy -0.8636 79.6036) (xy -0.8636 79.629) (xy 5.9436 79.629) (xy 5.9436 79.6036)
				(xy 5.9436 -0.8636) (xy 5.9436 -0.889) (xy -0.8636 -0.889)
			)
			(stroke
				(width 0)
				(type default)
			)
			(fill no)
			(layer "B.CrtYd")
		)
		(fp_rect
			(start -2.135124 -4.560062)
			(end 7.21487 83.300062)
			(stroke
				(width 0)
				(type default)
			)
			(fill no)
			(layer "F.CrtYd")
		)
		(fp_line
			(start -2.135124 -4.560062)
			(end 7.215124 -4.560062)
			(stroke
				(width 0.1)
				(type default)
			)
			(layer "F.Fab")
		)
		(fp_line
			(start -2.135124 83.300062)
			(end -2.135124 -4.560062)
			(stroke
				(width 0.1)
				(type default)
			)
			(layer "F.Fab")
		)
		(fp_line
			(start 7.215124 -4.560062)
			(end 7.215124 83.300062)
			(stroke
				(width 0.1)
				(type default)
			)
			(layer "F.Fab")
		)
		(fp_line
			(start 7.215124 83.300062)
			(end -2.135124 83.300062)
			(stroke
				(width 0.1)
				(type default)
			)
			(layer "F.Fab")
		)
		(fp_text user "1"
			(at -3.01625 -0.658368 0)
			(unlocked yes)
			(layer "F.SilkS")
			(effects
				(font
					(size 0.7874 0.5842)
					(thickness 0.1524)
				)
				(justify left)
			)
		)
		(fp_text user "32"
			(at -1.971802 79.99095 0)
			(unlocked yes)
			(layer "F.SilkS")
			(effects
				(font
					(size 0.7874 0.5842)
					(thickness 0.1524)
				)
				(justify left)
			)
		)
		(fp_text user "33"
			(at 7.57428 78.22184 0)
			(unlocked yes)
			(layer "F.SilkS")
			(effects
				(font
					(size 0.7874 0.5842)
					(thickness 0.1524)
				)
				(justify left)
			)
		)
		(fp_text user "64"
			(at 7.666736 -0.128016 0)
			(unlocked yes)
			(layer "F.SilkS")
			(effects
				(font
					(size 0.7874 0.5842)
					(thickness 0.1524)
				)
				(justify left)
			)
		)
		(fp_text user "32"
			(at -1.060958 79.574644 0)
			(unlocked yes)
			(layer "B.SilkS")
			(effects
				(font
					(size 0.7874 0.5842)
					(thickness 0.1524)
				)
				(justify left mirror)
			)
		)
		(fp_text user "1"
			(at -1.044448 -0.912622 0)
			(unlocked yes)
			(layer "B.SilkS")
			(effects
				(font
					(size 0.7874 0.5842)
					(thickness 0.1524)
				)
				(justify left mirror)
			)
		)
		(fp_text user "64"
			(at 5.82168 -1.531112 0)
			(unlocked yes)
			(layer "B.SilkS")
			(effects
				(font
					(size 0.7874 0.5842)
					(thickness 0.1524)
				)
				(justify left mirror)
			)
		)
		(fp_text user "33"
			(at 6.15696 80.823308 0)
			(unlocked yes)
			(layer "B.SilkS")
			(effects
				(font
					(size 0.7874 0.5842)
					(thickness 0.1524)
				)
				(justify left mirror)
			)
		)
		(pad "1" thru_hole rect
			(at 0 0 270)
			(size 1.6256 1.6256)
			(drill 1.1176)
			(layers "*.Cu" "*.Mask")
			(remove_unused_layers no)
			(net "P12V")
			(clearance 0)
			(padstack
				(mode front_inner_back)
				(layer "Inner"
					(shape circle)
					(size 1.6256 1.6256)
					(clearance 0)
				)
				(layer "B.Cu"
					(shape rect)
					(size 1.6256 1.6256)
					(clearance 0)
				)
			)
		)
		(pad "2" thru_hole circle
			(at 0 2.54 270)
			(size 1.6256 1.6256)
			(drill 1.1176)
			(layers "*.Cu" "*.Mask")
			(remove_unused_layers no)
			(net "P12V")
			(clearance 0)
		)
		(pad "3" thru_hole circle
			(at 0 5.08 270)
			(size 1.6256 1.6256)
			(drill 1.1176)
			(layers "*.Cu" "*.Mask")
			(remove_unused_layers no)
			(net "P12V")
			(clearance 0)
		)
		(pad "4" thru_hole circle
			(at 0 7.62 270)
			(size 1.6256 1.6256)
			(drill 1.1176)
			(layers "*.Cu" "*.Mask")
			(remove_unused_layers no)
			(net "P12V")
			(clearance 0)
		)
		(pad "5" thru_hole circle
			(at 0 10.16 270)
			(size 1.6256 1.6256)
			(drill 1.1176)
			(layers "*.Cu" "*.Mask")
			(remove_unused_layers no)
			(net "P12V")
			(clearance 0)
		)
		(pad "6" thru_hole circle
			(at 0 12.7 270)
			(size 1.6256 1.6256)
			(drill 1.1176)
			(layers "*.Cu" "*.Mask")
			(remove_unused_layers no)
			(net "P12V")
			(clearance 0)
		)
		(pad "7" thru_hole circle
			(at 0 15.24 270)
			(size 1.6256 1.6256)
			(drill 1.1176)
			(layers "*.Cu" "*.Mask")
			(remove_unused_layers no)
			(net "P12V")
			(clearance 0)
		)
		(pad "8" thru_hole circle
			(at 0 17.78 270)
			(size 1.6256 1.6256)
			(drill 1.1176)
			(layers "*.Cu" "*.Mask")
			(remove_unused_layers no)
			(net "P12V")
			(clearance 0)
		)
		(pad "9" thru_hole circle
			(at 0 20.32 270)
			(size 1.6256 1.6256)
			(drill 1.1176)
			(layers "*.Cu" "*.Mask")
			(remove_unused_layers no)
			(net "P12V")
			(clearance 0)
		)
		(pad "10" thru_hole circle
			(at 0 22.86 270)
			(size 1.6256 1.6256)
			(drill 1.1176)
			(layers "*.Cu" "*.Mask")
			(remove_unused_layers no)
			(net "P12V")
			(clearance 0)
		)
		(pad "11" thru_hole circle
			(at 0 25.4 270)
			(size 1.6256 1.6256)
			(drill 1.1176)
			(layers "*.Cu" "*.Mask")
			(remove_unused_layers no)
			(net "P12V")
			(clearance 0)
		)
		(pad "12" thru_hole circle
			(at 0 27.94 270)
			(size 1.6256 1.6256)
			(drill 1.1176)
			(layers "*.Cu" "*.Mask")
			(remove_unused_layers no)
			(net "P12V")
			(clearance 0)
		)
		(pad "13" thru_hole circle
			(at 0 30.48 270)
			(size 1.6256 1.6256)
			(drill 1.1176)
			(layers "*.Cu" "*.Mask")
			(remove_unused_layers no)
			(net "GND")
			(clearance 0)
		)
		(pad "14" thru_hole circle
			(at 0 33.02 270)
			(size 1.6256 1.6256)
			(drill 1.1176)
			(layers "*.Cu" "*.Mask")
			(remove_unused_layers no)
			(net "GND")
			(clearance 0)
		)
		(pad "15" thru_hole circle
			(at 0 35.56 270)
			(size 1.6256 1.6256)
			(drill 1.1176)
			(layers "*.Cu" "*.Mask")
			(remove_unused_layers no)
			(net "GND")
			(clearance 0)
		)
		(pad "16" thru_hole circle
			(at 0 38.1 270)
			(size 1.6256 1.6256)
			(drill 1.1176)
			(layers "*.Cu" "*.Mask")
			(remove_unused_layers no)
			(net "GND")
			(clearance 0)
		)
		(pad "17" thru_hole circle
			(at 0 40.64 270)
			(size 1.6256 1.6256)
			(drill 1.1176)
			(layers "*.Cu" "*.Mask")
			(remove_unused_layers no)
			(net "GND")
			(clearance 0)
		)
		(pad "18" thru_hole circle
			(at 0 43.18 270)
			(size 1.6256 1.6256)
			(drill 1.1176)
			(layers "*.Cu" "*.Mask")
			(remove_unused_layers no)
			(net "GND")
			(clearance 0)
		)
		(pad "19" thru_hole circle
			(at 0 45.72 270)
			(size 1.6256 1.6256)
			(drill 1.1176)
			(layers "*.Cu" "*.Mask")
			(remove_unused_layers no)
			(net "GND")
			(clearance 0)
		)
		(pad "20" thru_hole circle
			(at 0 48.26 270)
			(size 1.6256 1.6256)
			(drill 1.1176)
			(layers "*.Cu" "*.Mask")
			(remove_unused_layers no)
			(net "GND")
			(clearance 0)
		)
		(pad "21" thru_hole circle
			(at 0 50.8 270)
			(size 1.6256 1.6256)
			(drill 1.1176)
			(layers "*.Cu" "*.Mask")
			(remove_unused_layers no)
			(net "GND")
			(clearance 0)
		)
		(pad "22" thru_hole circle
			(at 0 53.34 270)
			(size 1.6256 1.6256)
			(drill 1.1176)
			(layers "*.Cu" "*.Mask")
			(remove_unused_layers no)
			(net "GND")
			(clearance 0)
		)
		(pad "23" thru_hole circle
			(at 0 55.88 270)
			(size 1.6256 1.6256)
			(drill 1.1176)
			(layers "*.Cu" "*.Mask")
			(remove_unused_layers no)
			(net "GND")
			(clearance 0)
		)
		(pad "24" thru_hole circle
			(at 0 58.42 270)
			(size 1.6256 1.6256)
			(drill 1.1176)
			(layers "*.Cu" "*.Mask")
			(remove_unused_layers no)
			(net "GND")
			(clearance 0)
		)
		(pad "25" thru_hole circle
			(at 0 60.96 270)
			(size 1.6256 1.6256)
			(drill 1.1176)
			(layers "*.Cu" "*.Mask")
			(remove_unused_layers no)
			(net "Net_407")
			(clearance 0)
		)
		(pad "26" thru_hole circle
			(at 0 63.5 270)
			(size 1.6256 1.6256)
			(drill 1.1176)
			(layers "*.Cu" "*.Mask")
			(remove_unused_layers no)
			(net "PSU1_REMOTE_N")
			(clearance 0)
		)
		(pad "27" thru_hole circle
			(at 0 66.04 270)
			(size 1.6256 1.6256)
			(drill 1.1176)
			(layers "*.Cu" "*.Mask")
			(remove_unused_layers no)
			(net "PSU1_AC_OK")
			(clearance 0)
		)
		(pad "28" thru_hole circle
			(at 0 68.58 270)
			(size 1.6256 1.6256)
			(drill 1.1176)
			(layers "*.Cu" "*.Mask")
			(remove_unused_layers no)
			(net "PSU1_CSAHRE")
			(clearance 0)
		)
		(pad "29" thru_hole circle
			(at 0 71.12 270)
			(size 1.6256 1.6256)
			(drill 1.1176)
			(layers "*.Cu" "*.Mask")
			(remove_unused_layers no)
			(net "PSU1_PS_ON_N")
			(clearance 0)
		)
		(pad "30" thru_hole circle
			(at 0 73.66 270)
			(size 1.6256 1.6256)
			(drill 1.1176)
			(layers "*.Cu" "*.Mask")
			(remove_unused_layers no)
			(net "PSU1_PS_KILL")
			(clearance 0)
		)
		(pad "31" thru_hole circle
			(at 0 76.2 270)
			(size 1.6256 1.6256)
			(drill 1.1176)
			(layers "*.Cu" "*.Mask")
			(remove_unused_layers no)
			(net "PSU1_RESET")
			(clearance 0)
		)
		(pad "32" thru_hole circle
			(at 0 78.74 270)
			(size 1.6256 1.6256)
			(drill 1.1176)
			(layers "*.Cu" "*.Mask")
			(remove_unused_layers no)
			(net "PSU_ALERT_N")
			(clearance 0)
		)
		(pad "33" thru_hole circle
			(at 5.08 78.74 270)
			(size 1.6256 1.6256)
			(drill 1.1176)
			(layers "*.Cu" "*.Mask")
			(remove_unused_layers no)
			(net "I2C_PSU1_SDA")
			(clearance 0)
		)
		(pad "34" thru_hole circle
			(at 5.08 76.2 270)
			(size 1.6256 1.6256)
			(drill 1.1176)
			(layers "*.Cu" "*.Mask")
			(remove_unused_layers no)
			(net "Net_408")
			(clearance 0)
		)
		(pad "35" thru_hole circle
			(at 5.08 73.66 270)
			(size 1.6256 1.6256)
			(drill 1.1176)
			(layers "*.Cu" "*.Mask")
			(remove_unused_layers no)
			(net "I2C_PSU1_SCL")
			(clearance 0)
		)
		(pad "36" thru_hole circle
			(at 5.08 71.12 270)
			(size 1.6256 1.6256)
			(drill 1.1176)
			(layers "*.Cu" "*.Mask")
			(remove_unused_layers no)
			(net "PSU1_RETURN")
			(clearance 0)
		)
		(pad "37" thru_hole circle
			(at 5.08 68.58 270)
			(size 1.6256 1.6256)
			(drill 1.1176)
			(layers "*.Cu" "*.Mask")
			(remove_unused_layers no)
			(net "PSU1_DC_OK")
			(clearance 0)
		)
		(pad "38" thru_hole circle
			(at 5.08 66.04 270)
			(size 1.6256 1.6256)
			(drill 1.1176)
			(layers "*.Cu" "*.Mask")
			(remove_unused_layers no)
			(net "PSU1_AD0")
			(clearance 0)
		)
		(pad "39" thru_hole circle
			(at 5.08 63.5 270)
			(size 1.6256 1.6256)
			(drill 1.1176)
			(layers "*.Cu" "*.Mask")
			(remove_unused_layers no)
			(net "P12V_STBY")
			(clearance 0)
		)
		(pad "40" thru_hole circle
			(at 5.08 60.96 270)
			(size 1.6256 1.6256)
			(drill 1.1176)
			(layers "*.Cu" "*.Mask")
			(remove_unused_layers no)
			(net "PSU1_REMOTE_P")
			(clearance 0)
		)
		(pad "41" thru_hole circle
			(at 5.08 58.42 270)
			(size 1.6256 1.6256)
			(drill 1.1176)
			(layers "*.Cu" "*.Mask")
			(remove_unused_layers no)
			(net "GND")
			(clearance 0)
		)
		(pad "42" thru_hole circle
			(at 5.08 55.88 270)
			(size 1.6256 1.6256)
			(drill 1.1176)
			(layers "*.Cu" "*.Mask")
			(remove_unused_layers no)
			(net "GND")
			(clearance 0)
		)
		(pad "43" thru_hole circle
			(at 5.08 53.34 270)
			(size 1.6256 1.6256)
			(drill 1.1176)
			(layers "*.Cu" "*.Mask")
			(remove_unused_layers no)
			(net "GND")
			(clearance 0)
		)
		(pad "44" thru_hole circle
			(at 5.08 50.8 270)
			(size 1.6256 1.6256)
			(drill 1.1176)
			(layers "*.Cu" "*.Mask")
			(remove_unused_layers no)
			(net "GND")
			(clearance 0)
		)
		(pad "45" thru_hole circle
			(at 5.08 48.26 270)
			(size 1.6256 1.6256)
			(drill 1.1176)
			(layers "*.Cu" "*.Mask")
			(remove_unused_layers no)
			(net "GND")
			(clearance 0)
		)
		(pad "46" thru_hole circle
			(at 5.08 45.72 270)
			(size 1.6256 1.6256)
			(drill 1.1176)
			(layers "*.Cu" "*.Mask")
			(remove_unused_layers no)
			(net "GND")
			(clearance 0)
		)
		(pad "47" thru_hole circle
			(at 5.08 43.18 270)
			(size 1.6256 1.6256)
			(drill 1.1176)
			(layers "*.Cu" "*.Mask")
			(remove_unused_layers no)
			(net "GND")
			(clearance 0)
		)
		(pad "48" thru_hole circle
			(at 5.08 40.64 270)
			(size 1.6256 1.6256)
			(drill 1.1176)
			(layers "*.Cu" "*.Mask")
			(remove_unused_layers no)
			(net "GND")
			(clearance 0)
		)
		(pad "49" thru_hole circle
			(at 5.08 38.1 270)
			(size 1.6256 1.6256)
			(drill 1.1176)
			(layers "*.Cu" "*.Mask")
			(remove_unused_layers no)
			(net "GND")
			(clearance 0)
		)
		(pad "50" thru_hole circle
			(at 5.08 35.56 270)
			(size 1.6256 1.6256)
			(drill 1.1176)
			(layers "*.Cu" "*.Mask")
			(remove_unused_layers no)
			(net "GND")
			(clearance 0)
		)
		(pad "51" thru_hole circle
			(at 5.08 33.02 270)
			(size 1.6256 1.6256)
			(drill 1.1176)
			(layers "*.Cu" "*.Mask")
			(remove_unused_layers no)
			(net "GND")
			(clearance 0)
		)
		(pad "52" thru_hole circle
			(at 5.08 30.48 270)
			(size 1.6256 1.6256)
			(drill 1.1176)
			(layers "*.Cu" "*.Mask")
			(remove_unused_layers no)
			(net "GND")
			(clearance 0)
		)
		(pad "53" thru_hole circle
			(at 5.08 27.94 270)
			(size 1.6256 1.6256)
			(drill 1.1176)
			(layers "*.Cu" "*.Mask")
			(remove_unused_layers no)
			(net "P12V")
			(clearance 0)
		)
		(pad "54" thru_hole circle
			(at 5.08 25.4 270)
			(size 1.6256 1.6256)
			(drill 1.1176)
			(layers "*.Cu" "*.Mask")
			(remove_unused_layers no)
			(net "P12V")
			(clearance 0)
		)
		(pad "55" thru_hole circle
			(at 5.08 22.86 270)
			(size 1.6256 1.6256)
			(drill 1.1176)
			(layers "*.Cu" "*.Mask")
			(remove_unused_layers no)
			(net "P12V")
			(clearance 0)
		)
		(pad "56" thru_hole circle
			(at 5.08 20.32 270)
			(size 1.6256 1.6256)
			(drill 1.1176)
			(layers "*.Cu" "*.Mask")
			(remove_unused_layers no)
			(net "P12V")
			(clearance 0)
		)
		(pad "57" thru_hole circle
			(at 5.08 17.78 270)
			(size 1.6256 1.6256)
			(drill 1.1176)
			(layers "*.Cu" "*.Mask")
			(remove_unused_layers no)
			(net "P12V")
			(clearance 0)
		)
		(pad "58" thru_hole circle
			(at 5.08 15.24 270)
			(size 1.6256 1.6256)
			(drill 1.1176)
			(layers "*.Cu" "*.Mask")
			(remove_unused_layers no)
			(net "P12V")
			(clearance 0)
		)
		(pad "59" thru_hole circle
			(at 5.08 12.7 270)
			(size 1.6256 1.6256)
			(drill 1.1176)
			(layers "*.Cu" "*.Mask")
			(remove_unused_layers no)
			(net "P12V")
			(clearance 0)
		)
		(pad "60" thru_hole circle
			(at 5.08 10.16 270)
			(size 1.6256 1.6256)
			(drill 1.1176)
			(layers "*.Cu" "*.Mask")
			(remove_unused_layers no)
			(net "P12V")
			(clearance 0)
		)
		(pad "61" thru_hole circle
			(at 5.08 7.62 270)
			(size 1.6256 1.6256)
			(drill 1.1176)
			(layers "*.Cu" "*.Mask")
			(remove_unused_layers no)
			(net "P12V")
			(clearance 0)
		)
		(pad "62" thru_hole circle
			(at 5.08 5.08 270)
			(size 1.6256 1.6256)
			(drill 1.1176)
			(layers "*.Cu" "*.Mask")
			(remove_unused_layers no)
			(net "P12V")
			(clearance 0)
		)
		(pad "63" thru_hole circle
			(at 5.08 2.54 270)
			(size 1.6256 1.6256)
			(drill 1.1176)
			(layers "*.Cu" "*.Mask")
			(remove_unused_layers no)
			(net "P12V")
			(clearance 0)
		)
		(pad "64" thru_hole circle
			(at 5.08 0 270)
			(size 1.6256 1.6256)
			(drill 1.1176)
			(layers "*.Cu" "*.Mask")
			(remove_unused_layers no)
			(net "P12V")
			(clearance 0)
		)
	)
	(footprint ""
		(layer "F.Cu")
		(at 27.239976 -461.829912)
		(property "Reference" "R22"
			(at -3.353816 -0.093726 0)
			(unlocked yes)
			(layer "F.SilkS")
			(effects
				(font
					(size 0.7874 0.5842)
					(thickness 0.1524)
				)
				(justify left)
			)
		)
		(property "Value" ""
			(at 0 0 0)
			(layer "F.Fab")
			(effects
				(font
					(size 1.27 1.27)
				)
			)
		)
		(duplicate_pad_numbers_are_jumpers no)
		(fp_line
			(start -0.7874 -0.4064)
			(end 0.7874 -0.4064)
			(stroke
				(width 0.1524)
				(type default)
			)
			(layer "F.SilkS")
		)
		(fp_line
			(start -0.7874 0.4064)
			(end -0.7874 -0.4064)
			(stroke
				(width 0.1524)
				(type default)
			)
			(layer "F.SilkS")
		)
		(fp_line
			(start 0.7874 -0.4064)
			(end 0.7874 0.4064)
			(stroke
				(width 0.1524)
				(type default)
			)
			(layer "F.SilkS")
		)
		(fp_line
			(start 0.7874 0.4064)
			(end -0.7874 0.4064)
			(stroke
				(width 0.1524)
				(type default)
			)
			(layer "F.SilkS")
		)
		(fp_poly
			(pts
				(xy -0.508 0.2794) (xy -0.508 0.2286) (xy -0.635 0.2286) (xy -0.635 -0.254) (xy -0.5334 -0.254)
				(xy -0.5334 -0.2794) (xy 0.5334 -0.2794) (xy 0.5334 -0.254) (xy 0.635 -0.254) (xy 0.635 0.254) (xy 0.5334 0.254)
				(xy 0.5334 0.2794)
			)
			(stroke
				(width 0)
				(type default)
			)
			(fill no)
			(layer "F.CrtYd")
		)
		(pad "1" smd rect
			(at 0.40005 0)
			(size 0.4572 0.508)
			(layers "F.Cu" "F.Mask" "F.Paste")
			(net "PSU6_REMOTE_N")
		)
		(pad "2" smd rect
			(at -0.40005 0)
			(size 0.4572 0.508)
			(layers "F.Cu" "F.Mask" "F.Paste")
			(net "GND")
		)
	)
)
